# T6G (Grand Teton) — schematic netlist excerpt (pin names and nets, part order shuffled) for the footprints in the layout excerpt that follows; sources: Cadence DE-HDL packaged netlist, KiCad conversion of 04192023_DAF0TMB3IC0_F0TG_MB_C_brd_V02_OCP.brd

C2429  Q_CAP  22UF 4V 20% X6S  pkg C0402  page 74 : A = PVDDCR_SOC_P1 ; B = GND
PR2517  Q_RES  10 1% CHIP  pkg 0402LF  page 266 : A = P12V_HSC_ADC_N ; B = P12V_HSC_SENSE2_R3_N

(kicad_pcb
	(version 20260206)
	(generator "pcbnew")
	(generator_version "10.0")
	(general
		(thickness 1.6)
		(legacy_teardrops no)
	)
	(paper "A4")
	(title_block
		(title "04192023_DAF0TMB3IC0_F0TG_MB_C_brd_V02_OCP.brd")
		(comment 1 "Grand Teton / footprints 4994-4995 of 8354")
	)
	(layers
		(0 "F.Cu" signal "TOP")
		(4 "In1.Cu" signal "GND")
		(6 "In2.Cu" signal "IN1")
		(8 "In3.Cu" signal "GND1")
		(10 "In4.Cu" signal "IN2")
		(12 "In5.Cu" signal "GND2")
		(14 "In6.Cu" signal "IN3")
		(16 "In7.Cu" signal "GND3")
		(18 "In8.Cu" signal "VCC")
		(20 "In9.Cu" signal "VCC1")
		(22 "In10.Cu" signal "GND4")
		(24 "In11.Cu" signal "IN4")
		(26 "In12.Cu" signal "GND5")
		(28 "In13.Cu" signal "IN5")
		(30 "In14.Cu" signal "GND6")
		(32 "In15.Cu" signal "IN6")
		(34 "In16.Cu" signal "GND7")
		(2 "B.Cu" signal "BOTTOM")
		(9 "F.Adhes" user "F.Adhesive")
		(11 "B.Adhes" user "B.Adhesive")
		(13 "F.Paste" user "Package Geometry/Pastemask Top")
		(15 "B.Paste" user "Package Geometry/Pastemask Bottom")
		(5 "F.SilkS" user "Ref Des/Silkscreen Top")
		(7 "B.SilkS" user "Ref Des/Silkscreen Bottom")
		(1 "F.Mask" user "Board Geometry/Soldermask Top")
		(3 "B.Mask" user "Board Geometry/Soldermask Bottom")
		(17 "Dwgs.User" user "User.Drawings")
		(19 "Cmts.User" user "User.Comments")
		(21 "Eco1.User" user "User.Eco1")
		(23 "Eco2.User" user "User.Eco2")
		(25 "Edge.Cuts" user "Board Geometry/Outline")
		(27 "Margin" user)
		(31 "F.CrtYd" user "Package Geometry/Place Bound Top")
		(29 "B.CrtYd" user "Package Geometry/Place Bound Bottom")
		(35 "F.Fab" user "Ref Des/Assembly Top")
		(33 "B.Fab" user "Ref Des/Assembly Bottom")
	)
	(footprint ""
		(layer "B.Cu")
		(at 123.611386 -252.543564)
		(property "Reference" "C2429"
			(at 0 0 0)
			(layer "B.SilkS")
			(hide yes)
			(effects
				(font
					(size 1.27 1.27)
				)
				(justify mirror)
			)
		)
		(property "Value" ""
			(at 0 0 0)
			(layer "B.Fab")
			(effects
				(font
					(size 1.27 1.27)
				)
				(justify mirror)
			)
		)
		(duplicate_pad_numbers_are_jumpers no)
		(fp_line
			(start -0.7874 -0.4064)
			(end -0.7874 0.4064)
			(stroke
				(width 0.1524)
				(type default)
			)
			(layer "B.SilkS")
		)
		(fp_line
			(start -0.7874 0.4064)
			(end 0.7874 0.4064)
			(stroke
				(width 0.1524)
				(type default)
			)
			(layer "B.SilkS")
		)
		(fp_line
			(start 0.7874 -0.4064)
			(end -0.7874 -0.4064)
			(stroke
				(width 0.1524)
				(type default)
			)
			(layer "B.SilkS")
		)
		(fp_line
			(start 0.7874 0.4064)
			(end 0.7874 -0.4064)
			(stroke
				(width 0.1524)
				(type default)
			)
			(layer "B.SilkS")
		)
		(fp_line
			(start -0.67945 -0.3048)
			(end -0.67945 0.3048)
			(stroke
				(width 0.1)
				(type default)
			)
			(layer "B.Fab")
		)
		(fp_line
			(start -0.67945 0.3048)
			(end -0.120396 0.3048)
			(stroke
				(width 0.1)
				(type default)
			)
			(layer "B.Fab")
		)
		(fp_line
			(start -0.12065 -0.3048)
			(end -0.67945 -0.3048)
			(stroke
				(width 0.1)
				(type default)
			)
			(layer "B.Fab")
		)
		(fp_line
			(start -0.12065 -0.2794)
			(end -0.12065 -0.3048)
			(stroke
				(width 0.1)
				(type default)
			)
			(layer "B.Fab")
		)
		(fp_line
			(start -0.120396 0.2794)
			(end 0.12065 0.2794)
			(stroke
				(width 0.1)
				(type default)
			)
			(layer "B.Fab")
		)
		(fp_line
			(start -0.120396 0.3048)
			(end -0.120396 0.2794)
			(stroke
				(width 0.1)
				(type default)
			)
			(layer "B.Fab")
		)
		(fp_line
			(start 0.12065 -0.305054)
			(end 0.12065 -0.2794)
			(stroke
				(width 0.1)
				(type default)
			)
			(layer "B.Fab")
		)
		(fp_line
			(start 0.12065 -0.2794)
			(end -0.12065 -0.2794)
			(stroke
				(width 0.1)
				(type default)
			)
			(layer "B.Fab")
		)
		(fp_line
			(start 0.12065 0.2794)
			(end 0.12065 0.3048)
			(stroke
				(width 0.1)
				(type default)
			)
			(layer "B.Fab")
		)
		(fp_line
			(start 0.12065 0.3048)
			(end 0.67945 0.3048)
			(stroke
				(width 0.1)
				(type default)
			)
			(layer "B.Fab")
		)
		(fp_line
			(start 0.67945 -0.305054)
			(end 0.12065 -0.305054)
			(stroke
				(width 0.1)
				(type default)
			)
			(layer "B.Fab")
		)
		(fp_line
			(start 0.67945 0.3048)
			(end 0.67945 -0.305054)
			(stroke
				(width 0.1)
				(type default)
			)
			(layer "B.Fab")
		)
		(pad "1" smd circle
			(at 0.40005 0 180)
			(size 0 0)
			(layers "B.Cu" "B.Mask" "B.Paste")
			(net "PVDDCR_SOC_P1")
		)
		(pad "2" smd circle
			(at -0.40005 0 180)
			(size 0 0)
			(layers "B.Cu" "B.Mask" "B.Paste")
			(net "GND")
		)
	)
	(footprint ""
		(layer "B.Cu")
		(at 208.461356 -381.222504)
		(property "Reference" "PR2517"
			(at 0 0 0)
			(layer "B.SilkS")
			(hide yes)
			(effects
				(font
					(size 1.27 1.27)
				)
				(justify mirror)
			)
		)
		(property "Value" ""
			(at 0 0 0)
			(layer "B.Fab")
			(effects
				(font
					(size 1.27 1.27)
				)
				(justify mirror)
			)
		)
		(duplicate_pad_numbers_are_jumpers no)
		(fp_line
			(start -0.7874 -0.4064)
			(end -0.7874 0.4064)
			(stroke
				(width 0.1524)
				(type default)
			)
			(layer "B.SilkS")
		)
		(fp_line
			(start -0.7874 0.4064)
			(end 0.7874 0.4064)
			(stroke
				(width 0.1524)
				(type default)
			)
			(layer "B.SilkS")
		)
		(fp_line
			(start 0.7874 -0.4064)
			(end -0.7874 -0.4064)
			(stroke
				(width 0.1524)
				(type default)
			)
			(layer "B.SilkS")
		)
		(fp_line
			(start 0.7874 0.4064)
			(end 0.7874 -0.4064)
			(stroke
				(width 0.1524)
				(type default)
			)
			(layer "B.SilkS")
		)
		(fp_line
			(start -0.67945 -0.3048)
			(end -0.67945 0.3048)
			(stroke
				(width 0.1)
				(type default)
			)
			(layer "B.Fab")
		)
		(fp_line
			(start -0.67945 0.3048)
			(end -0.120396 0.3048)
			(stroke
				(width 0.1)
				(type default)
			)
			(layer "B.Fab")
		)
		(fp_line
			(start -0.12065 -0.3048)
			(end -0.67945 -0.3048)
			(stroke
				(width 0.1)
				(type default)
			)
			(layer "B.Fab")
		)
		(fp_line
			(start -0.12065 -0.2794)
			(end -0.12065 -0.3048)
			(stroke
				(width 0.1)
				(type default)
			)
			(layer "B.Fab")
		)
		(fp_line
			(start -0.120396 0.2794)
			(end 0.12065 0.2794)
			(stroke
				(width 0.1)
				(type default)
			)
			(layer "B.Fab")
		)
		(fp_line
			(start -0.120396 0.3048)
			(end -0.120396 0.2794)
			(stroke
				(width 0.1)
				(type default)
			)
			(layer "B.Fab")
		)
		(fp_line
			(start 0.12065 -0.305054)
			(end 0.12065 -0.2794)
			(stroke
				(width 0.1)
				(type default)
			)
			(layer "B.Fab")
		)
		(fp_line
			(start 0.12065 -0.2794)
			(end -0.12065 -0.2794)
			(stroke
				(width 0.1)
				(type default)
			)
			(layer "B.Fab")
		)
		(fp_line
			(start 0.12065 0.2794)
			(end 0.12065 0.3048)
			(stroke
				(width 0.1)
				(type default)
			)
			(layer "B.Fab")
		)
		(fp_line
			(start 0.12065 0.3048)
			(end 0.67945 0.3048)
			(stroke
				(width 0.1)
				(type default)
			)
			(layer "B.Fab")
		)
		(fp_line
			(start 0.67945 -0.305054)
			(end 0.12065 -0.305054)
			(stroke
				(width 0.1)
				(type default)
			)
			(layer "B.Fab")
		)
		(fp_line
			(start 0.67945 0.3048)
			(end 0.67945 -0.305054)
			(stroke
				(width 0.1)
				(type default)
			)
			(layer "B.Fab")
		)
		(pad "1" smd circle
			(at 0.40005 0 180)
			(size 0 0)
			(layers "B.Cu" "B.Mask" "B.Paste")
			(net "P12V_HSC_ADC_N")
		)
		(pad "2" smd circle
			(at -0.40005 0 180)
			(size 0 0)
			(layers "B.Cu" "B.Mask" "B.Paste")
			(net "P12V_HSC_SENSE2_R3_N")
		)
	)
)
